(kicad_pcb
	(version 20260206)
	(generator "pcbnew")
	(generator_version "10.0")
	(general
		(thickness 1.6)
		(legacy_teardrops no)
	)
	(paper "A4")
	(title_block
		(title "Bryce Canyon_F.DPB_16315-1-OCP.brd")
		(comment 1 "Bryce Canyon / footprints 1-6 of 2223")
	)
	(layers
		(0 "F.Cu" signal "TOP")
		(4 "In1.Cu" signal "L2GND")
		(6 "In2.Cu" signal "L3")
		(8 "In3.Cu" signal "L4GND")
		(10 "In4.Cu" signal "L5")
		(12 "In5.Cu" signal "L6VCC")
		(14 "In6.Cu" signal "L7VCC")
		(16 "In7.Cu" signal "L8")
		(18 "In8.Cu" signal "L9GND")
		(20 "In9.Cu" signal "L10")
		(22 "In10.Cu" signal "L11GND")
		(2 "B.Cu" signal "BOTTOM")
		(9 "F.Adhes" user "F.Adhesive")
		(11 "B.Adhes" user "B.Adhesive")
		(13 "F.Paste" user "Package Geometry/Pastemask Top")
		(15 "B.Paste" user "Package Geometry/Pastemask Bottom")
		(5 "F.SilkS" user "Ref Des/Silkscreen Top")
		(7 "B.SilkS" user "Ref Des/Silkscreen Bottom")
		(1 "F.Mask" user "Board Geometry/Soldermask Top")
		(3 "B.Mask" user "Board Geometry/Soldermask Bottom")
		(17 "Dwgs.User" user "User.Drawings")
		(19 "Cmts.User" user "User.Comments")
		(21 "Eco1.User" user "User.Eco1")
		(23 "Eco2.User" user "User.Eco2")
		(25 "Edge.Cuts" user "Board Geometry/Outline")
		(27 "Margin" user)
		(31 "F.CrtYd" user "Package Geometry/Place Bound Top")
		(29 "B.CrtYd" user "Package Geometry/Place Bound Bottom")
		(35 "F.Fab" user "Ref Des/Assembly Top")
		(33 "B.Fab" user "Ref Des/Assembly Bottom")
	)
	(footprint ""
		(layer "F.Cu")
		(at 77.815948 -179.683918 -90)
		(property "Reference" "C228"
			(at 0 0 270)
			(layer "F.SilkS")
			(hide yes)
			(effects
				(font
					(size 1.27 1.27)
				)
			)
		)
		(property "Value" "SC4D7U25V5KX-1-GP"
			(at -0.0762 -6.1214 270)
			(unlocked yes)
			(layer "F.Fab")
			(hide yes)
			(effects
				(font
					(size 1.016 1.016)
					(thickness 0.1524)
				)
			)
		)
		(property "Device Type" "C805H58"
			(at -0.0762 -8.1534 270)
			(unlocked yes)
			(layer "F.Fab")
			(hide yes)
			(effects
				(font
					(size 1.016 1.016)
					(thickness 0.1524)
				)
			)
		)
		(duplicate_pad_numbers_are_jumpers no)
		(fp_line
			(start 0.635 0)
			(end -0.635 0)
			(stroke
				(width 0.508)
				(type default)
			)
			(layer "F.SilkS")
		)
		(fp_rect
			(start -0.9652 1.778)
			(end 0.9652 -1.778)
			(stroke
				(width 0)
				(type default)
			)
			(fill no)
			(layer "F.CrtYd")
		)
		(fp_poly
			(pts
				(xy -0.9652 -1.778) (xy 0.9652 -1.778) (xy 0.9652 1.778) (xy -0.9652 1.778)
			)
			(stroke
				(width 0)
				(type default)
			)
			(fill no)
			(layer "F.Fab")
		)
		(pad "1" smd rect
			(at 0 -0.9652 270)
			(size 1.397 1.143)
			(layers "F.Cu" "F.Mask" "F.Paste")
			(net "P12V_HDD14")
		)
		(pad "2" smd rect
			(at 0 0.9652 270)
			(size 1.397 1.143)
			(layers "F.Cu" "F.Mask" "F.Paste")
			(net "GND")
		)
	)
	(footprint ""
		(layer "F.Cu")
		(at 46.412658 -278.089106 90)
		(property "Reference" "R166"
			(at 0 0 90)
			(layer "F.SilkS")
			(hide yes)
			(effects
				(font
					(size 1.27 1.27)
				)
			)
		)
		(property "Value" "4K7R2J-2-GP"
			(at 0.064008 -3.993896 90)
			(unlocked yes)
			(layer "F.Fab")
			(hide yes)
			(effects
				(font
					(size 1.016 1.016)
					(thickness 0.1524)
				)
			)
		)
		(property "Device Type" "R402H16"
			(at 0.064008 -5.517896 90)
			(unlocked yes)
			(layer "F.Fab")
			(hide yes)
			(effects
				(font
					(size 1.016 1.016)
					(thickness 0.1524)
				)
			)
		)
		(duplicate_pad_numbers_are_jumpers no)
		(fp_line
			(start 0.508 -0.9398)
			(end -0.508 -0.9398)
			(stroke
				(width 0.1524)
				(type default)
			)
			(layer "F.SilkS")
		)
		(fp_line
			(start -0.508 -0.9398)
			(end -0.508 0.9398)
			(stroke
				(width 0.1524)
				(type default)
			)
			(layer "F.SilkS")
		)
		(fp_rect
			(start -0.508 0.9398)
			(end 0.508 -0.9398)
			(stroke
				(width 0)
				(type default)
			)
			(fill no)
			(layer "F.CrtYd")
		)
		(fp_rect
			(start -0.508 0.9398)
			(end 0.508 -0.9398)
			(stroke
				(width 0)
				(type default)
			)
			(fill no)
			(layer "F.Fab")
		)
		(pad "1" smd custom
			(at 0 -0.4445 90)
			(size 0.1397 0.1397)
			(layers "F.Cu" "F.Mask" "F.Paste")
			(net "P12V_A")
			(options
				(clearance outline)
				(anchor circle)
			)
			(primitives
				(gr_poly
					(pts
						(arc
							(start -0.1778 -0.2794)
							(mid -0.249642 -0.249642)
							(end -0.2794 -0.1778)
						)
						(arc
							(start -0.2794 0.1778)
							(mid -0.249642 0.249642)
							(end -0.1778 0.2794)
						)
						(arc
							(start 0.1778 0.2794)
							(mid 0.249642 0.249642)
							(end 0.2794 0.1778)
						)
						(arc
							(start 0.2794 -0.1778)
							(mid 0.249642 -0.249642)
							(end 0.1778 -0.2794)
						)
					)
					(width 0)
					(fill yes)
				)
			)
		)
		(pad "2" smd custom
			(at 0 0.4445 90)
			(size 0.1397 0.1397)
			(layers "F.Cu" "F.Mask" "F.Paste")
			(net "SW_HDD_R1")
			(options
				(clearance outline)
				(anchor circle)
			)
			(primitives
				(gr_poly
					(pts
						(arc
							(start -0.1778 -0.2794)
							(mid -0.249642 -0.249642)
							(end -0.2794 -0.1778)
						)
						(arc
							(start -0.2794 0.1778)
							(mid -0.249642 0.249642)
							(end -0.1778 0.2794)
						)
						(arc
							(start 0.1778 0.2794)
							(mid 0.249642 0.249642)
							(end 0.2794 0.1778)
						)
						(arc
							(start 0.2794 -0.1778)
							(mid 0.249642 -0.249642)
							(end 0.1778 -0.2794)
						)
					)
					(width 0)
					(fill yes)
				)
			)
		)
	)
	(footprint ""
		(layer "F.Cu")
		(at 256.47777 -380.367794)
		(property "Reference" "Q228"
			(at 0 0 0)
			(layer "F.SilkS")
			(hide yes)
			(effects
				(font
					(size 1.27 1.27)
				)
			)
		)
		(property "Value" "IRFH8201TRPBF-GP"
			(at -4.2164 -4.3688 0)
			(unlocked yes)
			(layer "F.Fab")
			(hide yes)
			(effects
				(font
					(size 1.016 1.016)
					(thickness 0.1524)
				)
			)
		)
		(property "Device Type" "PPAK-5PH42"
			(at -4.2164 -5.8928 0)
			(unlocked yes)
			(layer "F.Fab")
			(hide yes)
			(effects
				(font
					(size 1.016 1.016)
					(thickness 0.1524)
				)
			)
		)
		(duplicate_pad_numbers_are_jumpers no)
		(fp_line
			(start -3.0353 4.9276)
			(end -3.0353 3.9624)
			(stroke
				(width 0.3302)
				(type default)
			)
			(layer "F.SilkS")
		)
		(fp_line
			(start -2.8956 -2.794)
			(end 2.8956 -2.794)
			(stroke
				(width 0.1524)
				(type default)
			)
			(layer "F.SilkS")
		)
		(fp_line
			(start -2.8956 4.826)
			(end -2.8956 -2.794)
			(stroke
				(width 0.1524)
				(type default)
			)
			(layer "F.SilkS")
		)
		(fp_line
			(start -1.9431 4.9276)
			(end -3.0353 4.9276)
			(stroke
				(width 0.3302)
				(type default)
			)
			(layer "F.SilkS")
		)
		(fp_line
			(start 2.8956 -2.794)
			(end 2.8956 4.826)
			(stroke
				(width 0.1524)
				(type default)
			)
			(layer "F.SilkS")
		)
		(fp_line
			(start 2.8956 4.826)
			(end -2.8956 4.826)
			(stroke
				(width 0.1524)
				(type default)
			)
			(layer "F.SilkS")
		)
		(fp_poly
			(pts
				(xy -2.3622 5.334) (xy -1.4986 5.334) (xy -1.9304 4.9022)
			)
			(stroke
				(width 0)
				(type default)
			)
			(fill yes)
			(layer "F.SilkS")
		)
		(fp_poly
			(pts
				(xy -2.6416 -0.3556) (xy -0.3556 -0.3556) (xy -0.3556 -2.54) (xy -2.6416 -2.54)
			)
			(stroke
				(width 0)
				(type default)
			)
			(fill yes)
			(layer "F.Paste")
		)
		(fp_poly
			(pts
				(xy -2.6416 2.54) (xy -0.3556 2.54) (xy -0.3556 0.3556) (xy -2.6416 0.3556)
			)
			(stroke
				(width 0)
				(type default)
			)
			(fill yes)
			(layer "F.Paste")
		)
		(fp_poly
			(pts
				(xy 0.3556 -0.3556) (xy 2.6416 -0.3556) (xy 2.6416 -2.54) (xy 0.3556 -2.54)
			)
			(stroke
				(width 0)
				(type default)
			)
			(fill yes)
			(layer "F.Paste")
		)
		(fp_poly
			(pts
				(xy 0.3556 2.54) (xy 2.6416 2.54) (xy 2.6416 0.3556) (xy 0.3556 0.3556)
			)
			(stroke
				(width 0)
				(type default)
			)
			(fill yes)
			(layer "F.Paste")
		)
		(fp_rect
			(start -2.5781 3.9878)
			(end 2.5781 -2.1082)
			(stroke
				(width 0)
				(type default)
			)
			(fill no)
			(layer "F.CrtYd")
		)
		(fp_poly
			(pts
				(xy -3.1496 5.08) (xy -3.1496 -3.048) (xy 3.1496 -3.048) (xy 3.1496 3.9751) (xy 2.5781 3.9751) (xy 2.5781 -2.1082)
				(xy -2.5781 -2.1082) (xy -2.5781 3.9878) (xy 3.1496 3.9878) (xy 3.1496 5.08)
			)
			(stroke
				(width 0)
				(type default)
			)
			(fill no)
			(layer "F.CrtYd")
		)
		(fp_rect
			(start -3.1496 5.08)
			(end 3.1496 -3.048)
			(stroke
				(width 0)
				(type default)
			)
			(fill no)
			(layer "F.Fab")
		)
		(pad "1" smd rect
			(at -1.905 3.81)
			(size 0.762 1.524)
			(layers "F.Cu" "F.Mask" "F.Paste")
			(net "P12V_A")
		)
		(pad "2" smd rect
			(at -0.635 3.81)
			(size 0.762 1.524)
			(layers "F.Cu" "F.Mask" "F.Paste")
			(net "P12V_A")
		)
		(pad "3" smd rect
			(at 0.635 3.81)
			(size 0.762 1.524)
			(layers "F.Cu" "F.Mask" "F.Paste")
			(net "P12V_A")
		)
		(pad "4" smd rect
			(at 1.905 3.81)
			(size 0.762 1.524)
			(layers "F.Cu" "F.Mask" "F.Paste")
			(net "MB3_12V_CTRL_GATE3")
		)
		(pad "5" smd rect
			(at 0 0)
			(size 5.2832 5.08)
			(layers "F.Cu" "F.Mask" "F.Paste")
			(net "MB3_P12V_IN_R")
		)
		(pad "6" smd rect
			(at 0.635 -2.032)
			(size 0.0254 0.0254)
			(layers "F.Cu" "F.Mask" "F.Paste")
			(net "MB3_P12V_IN_R")
		)
		(pad "7" smd rect
			(at -0.635 -2.032)
			(size 0.0254 0.0254)
			(layers "F.Cu" "F.Mask" "F.Paste")
			(net "MB3_P12V_IN_R")
		)
		(pad "8" smd rect
			(at -1.905 -2.032)
			(size 0.0254 0.0254)
			(layers "F.Cu" "F.Mask" "F.Paste")
			(net "MB3_P12V_IN_R")
		)
	)
	(footprint ""
		(layer "F.Cu")
		(at 368.8588 -132.1054)
		(property "Reference" "C562"
			(at 0 0 0)
			(layer "F.SilkS")
			(hide yes)
			(effects
				(font
					(size 1.27 1.27)
				)
			)
		)
		(property "Value" "SCD1U25V2KX-2-GP"
			(at 1.1811 -2.7051 0)
			(unlocked yes)
			(layer "F.Fab")
			(hide yes)
			(effects
				(font
					(size 1.016 1.016)
					(thickness 0.1524)
				)
			)
		)
		(property "Device Type" "C402H22"
			(at 1.1811 -4.2291 0)
			(unlocked yes)
			(layer "F.Fab")
			(hide yes)
			(effects
				(font
					(size 1.016 1.016)
					(thickness 0.1524)
				)
			)
		)
		(duplicate_pad_numbers_are_jumpers no)
		(fp_rect
			(start -0.4318 0.9525)
			(end 0.4318 -0.9525)
			(stroke
				(width 0)
				(type default)
			)
			(fill no)
			(layer "F.CrtYd")
		)
		(fp_rect
			(start -0.4318 0.9525)
			(end 0.4318 -0.9525)
			(stroke
				(width 0)
				(type default)
			)
			(fill no)
			(layer "F.Fab")
		)
		(pad "1" smd custom
			(at 0 -0.4445)
			(size 0.1524 0.1524)
			(layers "F.Cu" "F.Mask" "F.Paste")
			(net "MB1_ISET_R")
			(options
				(clearance outline)
				(anchor circle)
			)
			(primitives
				(gr_poly
					(pts
						(arc
							(start 0.3048 -0.2032)
							(mid 0.275042 -0.275042)
							(end 0.2032 -0.3048)
						)
						(arc
							(start -0.2032 -0.3048)
							(mid -0.275042 -0.275042)
							(end -0.3048 -0.2032)
						)
						(arc
							(start -0.3048 0.2032)
							(mid -0.275042 0.275042)
							(end -0.2032 0.3048)
						)
						(arc
							(start 0.2032 0.3048)
							(mid 0.275042 0.275042)
							(end 0.3048 0.2032)
						)
					)
					(width 0)
					(fill yes)
				)
			)
		)
		(pad "2" smd custom
			(at 0 0.4445)
			(size 0.1524 0.1524)
			(layers "F.Cu" "F.Mask" "F.Paste")
			(net "AGND_CURRENT_MONOB")
			(options
				(clearance outline)
				(anchor circle)
			)
			(primitives
				(gr_poly
					(pts
						(arc
							(start 0.3048 -0.2032)
							(mid 0.275042 -0.275042)
							(end 0.2032 -0.3048)
						)
						(arc
							(start -0.2032 -0.3048)
							(mid -0.275042 -0.275042)
							(end -0.3048 -0.2032)
						)
						(arc
							(start -0.3048 0.2032)
							(mid -0.275042 0.275042)
							(end -0.2032 0.3048)
						)
						(arc
							(start 0.2032 0.3048)
							(mid 0.275042 0.275042)
							(end 0.3048 0.2032)
						)
					)
					(width 0)
					(fill yes)
				)
			)
		)
	)
	(footprint ""
		(layer "F.Cu")
		(at 142.818866 -145.372074 180)
		(property "Reference" "C542"
			(at 0 0 180)
			(layer "F.SilkS")
			(hide yes)
			(effects
				(font
					(size 1.27 1.27)
				)
			)
		)
		(property "Value" "SCD01U25V2KX-3GP"
			(at 1.1811 -2.7051 180)
			(unlocked yes)
			(layer "F.Fab")
			(hide yes)
			(effects
				(font
					(size 1.016 1.016)
					(thickness 0.1524)
				)
			)
		)
		(property "Device Type" "C402H22"
			(at 1.1811 -4.2291 180)
			(unlocked yes)
			(layer "F.Fab")
			(hide yes)
			(effects
				(font
					(size 1.016 1.016)
					(thickness 0.1524)
				)
			)
		)
		(duplicate_pad_numbers_are_jumpers no)
		(fp_rect
			(start -0.4318 0.9525)
			(end 0.4318 -0.9525)
			(stroke
				(width 0)
				(type default)
			)
			(fill no)
			(layer "F.CrtYd")
		)
		(fp_rect
			(start -0.4318 0.9525)
			(end 0.4318 -0.9525)
			(stroke
				(width 0)
				(type default)
			)
			(fill no)
			(layer "F.Fab")
		)
		(pad "1" smd custom
			(at 0 -0.4445 180)
			(size 0.1524 0.1524)
			(layers "F.Cu" "F.Mask" "F.Paste")
			(net "MB0_TIME_R")
			(options
				(clearance outline)
				(anchor circle)
			)
			(primitives
				(gr_poly
					(pts
						(arc
							(start 0.3048 -0.2032)
							(mid 0.275042 -0.275042)
							(end 0.2032 -0.3048)
						)
						(arc
							(start -0.2032 -0.3048)
							(mid -0.275042 -0.275042)
							(end -0.3048 -0.2032)
						)
						(arc
							(start -0.3048 0.2032)
							(mid -0.275042 0.275042)
							(end -0.2032 0.3048)
						)
						(arc
							(start 0.2032 0.3048)
							(mid 0.275042 0.275042)
							(end 0.3048 0.2032)
						)
					)
					(width 0)
					(fill yes)
				)
			)
		)
		(pad "2" smd custom
			(at 0 0.4445 180)
			(size 0.1524 0.1524)
			(layers "F.Cu" "F.Mask" "F.Paste")
			(net "AGND_CURRENT_MONOA")
			(options
				(clearance outline)
				(anchor circle)
			)
			(primitives
				(gr_poly
					(pts
						(arc
							(start 0.3048 -0.2032)
							(mid 0.275042 -0.275042)
							(end 0.2032 -0.3048)
						)
						(arc
							(start -0.2032 -0.3048)
							(mid -0.275042 -0.275042)
							(end -0.3048 -0.2032)
						)
						(arc
							(start -0.3048 0.2032)
							(mid -0.275042 0.275042)
							(end -0.2032 0.3048)
						)
						(arc
							(start 0.2032 0.3048)
							(mid 0.275042 0.275042)
							(end 0.3048 0.2032)
						)
					)
					(width 0)
					(fill yes)
				)
			)
		)
	)
	(footprint ""
		(layer "F.Cu")
		(at 336.9056 -45.735494 180)
		(property "Reference" "R834"
			(at 0 0 180)
			(layer "F.SilkS")
			(hide yes)
			(effects
				(font
					(size 1.27 1.27)
				)
			)
		)
		(property "Value" "4K7R2J-2-GP"
			(at 0.064008 -3.993896 180)
			(unlocked yes)
			(layer "F.Fab")
			(hide yes)
			(effects
				(font
					(size 1.016 1.016)
					(thickness 0.1524)
				)
			)
		)
		(property "Device Type" "R402H16"
			(at 0.064008 -5.517896 180)
			(unlocked yes)
			(layer "F.Fab")
			(hide yes)
			(effects
				(font
					(size 1.016 1.016)
					(thickness 0.1524)
				)
			)
		)
		(duplicate_pad_numbers_are_jumpers no)
		(fp_line
			(start 0.508 -0.9398)
			(end -0.508 -0.9398)
			(stroke
				(width 0.1524)
				(type default)
			)
			(layer "F.SilkS")
		)
		(fp_line
			(start -0.508 -0.9398)
			(end -0.508 0.9398)
			(stroke
				(width 0.1524)
				(type default)
			)
			(layer "F.SilkS")
		)
		(fp_rect
			(start -0.508 0.9398)
			(end 0.508 -0.9398)
			(stroke
				(width 0)
				(type default)
			)
			(fill no)
			(layer "F.CrtYd")
		)
		(fp_rect
			(start -0.508 0.9398)
			(end 0.508 -0.9398)
			(stroke
				(width 0)
				(type default)
			)
			(fill no)
			(layer "F.Fab")
		)
		(pad "1" smd custom
			(at 0 -0.4445 180)
			(size 0.1397 0.1397)
			(layers "F.Cu" "F.Mask" "F.Paste")
			(net "P12V_A")
			(options
				(clearance outline)
				(anchor circle)
			)
			(primitives
				(gr_poly
					(pts
						(arc
							(start -0.1778 -0.2794)
							(mid -0.249642 -0.249642)
							(end -0.2794 -0.1778)
						)
						(arc
							(start -0.2794 0.1778)
							(mid -0.249642 0.249642)
							(end -0.1778 0.2794)
						)
						(arc
							(start 0.1778 0.2794)
							(mid 0.249642 0.249642)
							(end 0.2794 0.1778)
						)
						(arc
							(start 0.2794 -0.1778)
							(mid 0.249642 -0.249642)
							(end 0.1778 -0.2794)
						)
					)
					(width 0)
					(fill yes)
				)
			)
		)
		(pad "2" smd custom
			(at 0 0.4445 180)
			(size 0.1397 0.1397)
			(layers "F.Cu" "F.Mask" "F.Paste")
			(net "SW_HDD_R30")
			(options
				(clearance outline)
				(anchor circle)
			)
			(primitives
				(gr_poly
					(pts
						(arc
							(start -0.1778 -0.2794)
							(mid -0.249642 -0.249642)
							(end -0.2794 -0.1778)
						)
						(arc
							(start -0.2794 0.1778)
							(mid -0.249642 0.249642)
							(end -0.1778 0.2794)
						)
						(arc
							(start 0.1778 0.2794)
							(mid 0.249642 0.249642)
							(end 0.2794 0.1778)
						)
						(arc
							(start 0.2794 -0.1778)
							(mid 0.249642 -0.249642)
							(end 0.1778 -0.2794)
						)
					)
					(width 0)
					(fill yes)
				)
			)
		)
	)
)
